(kicad_pcb
	(version 20260206)
	(generator "pcbnew")
	(generator_version "10.0")
	(general
		(thickness 1.6)
		(legacy_teardrops no)
	)
	(paper "A4")
	(title_block
		(title "03242023_DA0F0TMBIJ0_F0T_Motherboard_J_brd_V01_OCP.brd")
		(comment 1 "Grand Teton / footprints 4643-4648 of 6105")
	)
	(layers
		(0 "F.Cu" signal "TOP")
		(4 "In1.Cu" signal "GND")
		(6 "In2.Cu" signal "IN1")
		(8 "In3.Cu" signal "GND1")
		(10 "In4.Cu" signal "IN2")
		(12 "In5.Cu" signal "GND2")
		(14 "In6.Cu" signal "IN3")
		(16 "In7.Cu" signal "GND3")
		(18 "In8.Cu" signal "VCC")
		(20 "In9.Cu" signal "VCC1")
		(22 "In10.Cu" signal "GND4")
		(24 "In11.Cu" signal "IN4")
		(26 "In12.Cu" signal "GND5")
		(28 "In13.Cu" signal "IN5")
		(30 "In14.Cu" signal "GND6")
		(32 "In15.Cu" signal "IN6")
		(34 "In16.Cu" signal "GND7")
		(2 "B.Cu" signal "BOTTOM")
		(9 "F.Adhes" user "F.Adhesive")
		(11 "B.Adhes" user "B.Adhesive")
		(13 "F.Paste" user "Package Geometry/Pastemask Top")
		(15 "B.Paste" user "Package Geometry/Pastemask Bottom")
		(5 "F.SilkS" user "Ref Des/Silkscreen Top")
		(7 "B.SilkS" user "Ref Des/Silkscreen Bottom")
		(1 "F.Mask" user "Board Geometry/Soldermask Top")
		(3 "B.Mask" user "Board Geometry/Soldermask Bottom")
		(17 "Dwgs.User" user "User.Drawings")
		(19 "Cmts.User" user "User.Comments")
		(21 "Eco1.User" user "User.Eco1")
		(23 "Eco2.User" user "User.Eco2")
		(25 "Edge.Cuts" user "Board Geometry/Outline")
		(27 "Margin" user)
		(31 "F.CrtYd" user "Package Geometry/Place Bound Top")
		(29 "B.CrtYd" user "Package Geometry/Place Bound Bottom")
		(35 "F.Fab" user "Ref Des/Assembly Top")
		(33 "B.Fab" user "Ref Des/Assembly Bottom")
	)
	(footprint ""
		(layer "B.Cu")
		(at 231.52608 -118.760748 -90)
		(property "Reference" "R3637"
			(at 0 0 90)
			(layer "B.SilkS")
			(hide yes)
			(effects
				(font
					(size 1.27 1.27)
				)
				(justify mirror)
			)
		)
		(property "Value" ""
			(at 0 0 90)
			(layer "B.Fab")
			(effects
				(font
					(size 1.27 1.27)
				)
				(justify mirror)
			)
		)
		(duplicate_pad_numbers_are_jumpers no)
		(fp_line
			(start -0.7874 0.4064)
			(end 0.7874 0.4064)
			(stroke
				(width 0.1524)
				(type default)
			)
			(layer "B.SilkS")
		)
		(fp_line
			(start 0.7874 0.4064)
			(end 0.7874 -0.4064)
			(stroke
				(width 0.1524)
				(type default)
			)
			(layer "B.SilkS")
		)
		(fp_line
			(start -0.7874 -0.4064)
			(end -0.7874 0.4064)
			(stroke
				(width 0.1524)
				(type default)
			)
			(layer "B.SilkS")
		)
		(fp_line
			(start 0.7874 -0.4064)
			(end -0.7874 -0.4064)
			(stroke
				(width 0.1524)
				(type default)
			)
			(layer "B.SilkS")
		)
		(fp_line
			(start -0.67945 0.3048)
			(end -0.120396 0.3048)
			(stroke
				(width 0.1)
				(type default)
			)
			(layer "B.Fab")
		)
		(fp_line
			(start -0.120396 0.3048)
			(end -0.120396 0.2794)
			(stroke
				(width 0.1)
				(type default)
			)
			(layer "B.Fab")
		)
		(fp_line
			(start 0.12065 0.3048)
			(end 0.67945 0.3048)
			(stroke
				(width 0.1)
				(type default)
			)
			(layer "B.Fab")
		)
		(fp_line
			(start 0.67945 0.3048)
			(end 0.67945 -0.305054)
			(stroke
				(width 0.1)
				(type default)
			)
			(layer "B.Fab")
		)
		(fp_line
			(start -0.120396 0.2794)
			(end 0.12065 0.2794)
			(stroke
				(width 0.1)
				(type default)
			)
			(layer "B.Fab")
		)
		(fp_line
			(start 0.12065 0.2794)
			(end 0.12065 0.3048)
			(stroke
				(width 0.1)
				(type default)
			)
			(layer "B.Fab")
		)
		(fp_line
			(start -0.12065 -0.2794)
			(end -0.12065 -0.3048)
			(stroke
				(width 0.1)
				(type default)
			)
			(layer "B.Fab")
		)
		(fp_line
			(start 0.12065 -0.2794)
			(end -0.12065 -0.2794)
			(stroke
				(width 0.1)
				(type default)
			)
			(layer "B.Fab")
		)
		(fp_line
			(start -0.67945 -0.3048)
			(end -0.67945 0.3048)
			(stroke
				(width 0.1)
				(type default)
			)
			(layer "B.Fab")
		)
		(fp_line
			(start -0.12065 -0.3048)
			(end -0.67945 -0.3048)
			(stroke
				(width 0.1)
				(type default)
			)
			(layer "B.Fab")
		)
		(fp_line
			(start 0.12065 -0.305054)
			(end 0.12065 -0.2794)
			(stroke
				(width 0.1)
				(type default)
			)
			(layer "B.Fab")
		)
		(fp_line
			(start 0.67945 -0.305054)
			(end 0.12065 -0.305054)
			(stroke
				(width 0.1)
				(type default)
			)
			(layer "B.Fab")
		)
		(pad "1" smd circle
			(at 0.40005 0 90)
			(size 0 0)
			(layers "B.Cu" "B.Mask" "B.Paste")
			(net "OCP_SFF_CLK_OE_N")
		)
		(pad "2" smd circle
			(at -0.40005 0 90)
			(size 0 0)
			(layers "B.Cu" "B.Mask" "B.Paste")
			(net "FM_DB2000_12_OE_N")
		)
	)
	(footprint ""
		(layer "B.Cu")
		(at 178.871626 -415.633154 90)
		(property "Reference" "R2812"
			(at 0 0 90)
			(layer "B.SilkS")
			(hide yes)
			(effects
				(font
					(size 1.27 1.27)
				)
				(justify mirror)
			)
		)
		(property "Value" ""
			(at 0 0 90)
			(layer "B.Fab")
			(effects
				(font
					(size 1.27 1.27)
				)
				(justify mirror)
			)
		)
		(duplicate_pad_numbers_are_jumpers no)
		(fp_line
			(start 0.7874 -0.4064)
			(end -0.7874 -0.4064)
			(stroke
				(width 0.1524)
				(type default)
			)
			(layer "B.SilkS")
		)
		(fp_line
			(start -0.7874 -0.4064)
			(end -0.7874 0.4064)
			(stroke
				(width 0.1524)
				(type default)
			)
			(layer "B.SilkS")
		)
		(fp_line
			(start 0.7874 0.4064)
			(end 0.7874 -0.4064)
			(stroke
				(width 0.1524)
				(type default)
			)
			(layer "B.SilkS")
		)
		(fp_line
			(start -0.7874 0.4064)
			(end 0.7874 0.4064)
			(stroke
				(width 0.1524)
				(type default)
			)
			(layer "B.SilkS")
		)
		(fp_line
			(start 0.67945 -0.305054)
			(end 0.12065 -0.305054)
			(stroke
				(width 0.1)
				(type default)
			)
			(layer "B.Fab")
		)
		(fp_line
			(start 0.12065 -0.305054)
			(end 0.12065 -0.2794)
			(stroke
				(width 0.1)
				(type default)
			)
			(layer "B.Fab")
		)
		(fp_line
			(start -0.12065 -0.3048)
			(end -0.67945 -0.3048)
			(stroke
				(width 0.1)
				(type default)
			)
			(layer "B.Fab")
		)
		(fp_line
			(start -0.67945 -0.3048)
			(end -0.67945 0.3048)
			(stroke
				(width 0.1)
				(type default)
			)
			(layer "B.Fab")
		)
		(fp_line
			(start 0.12065 -0.2794)
			(end -0.12065 -0.2794)
			(stroke
				(width 0.1)
				(type default)
			)
			(layer "B.Fab")
		)
		(fp_line
			(start -0.12065 -0.2794)
			(end -0.12065 -0.3048)
			(stroke
				(width 0.1)
				(type default)
			)
			(layer "B.Fab")
		)
		(fp_line
			(start 0.12065 0.2794)
			(end 0.12065 0.3048)
			(stroke
				(width 0.1)
				(type default)
			)
			(layer "B.Fab")
		)
		(fp_line
			(start -0.120396 0.2794)
			(end 0.12065 0.2794)
			(stroke
				(width 0.1)
				(type default)
			)
			(layer "B.Fab")
		)
		(fp_line
			(start 0.67945 0.3048)
			(end 0.67945 -0.305054)
			(stroke
				(width 0.1)
				(type default)
			)
			(layer "B.Fab")
		)
		(fp_line
			(start 0.12065 0.3048)
			(end 0.67945 0.3048)
			(stroke
				(width 0.1)
				(type default)
			)
			(layer "B.Fab")
		)
		(fp_line
			(start -0.120396 0.3048)
			(end -0.120396 0.2794)
			(stroke
				(width 0.1)
				(type default)
			)
			(layer "B.Fab")
		)
		(fp_line
			(start -0.67945 0.3048)
			(end -0.120396 0.3048)
			(stroke
				(width 0.1)
				(type default)
			)
			(layer "B.Fab")
		)
		(pad "1" smd circle
			(at 0.40005 0 270)
			(size 0 0)
			(layers "B.Cu" "B.Mask" "B.Paste")
			(net "SMB_FAN_3V3AUX_BUF_SDA")
		)
		(pad "2" smd circle
			(at -0.40005 0 270)
			(size 0 0)
			(layers "B.Cu" "B.Mask" "B.Paste")
			(net "SMB_FAN_3V3AUX_BUF_R_SDA")
		)
	)
	(footprint ""
		(layer "B.Cu")
		(at 137.80262 -30.157928 -90)
		(property "Reference" "C2324"
			(at 0 0 90)
			(layer "B.SilkS")
			(hide yes)
			(effects
				(font
					(size 1.27 1.27)
				)
				(justify mirror)
			)
		)
		(property "Value" ""
			(at 0 0 90)
			(layer "B.Fab")
			(effects
				(font
					(size 1.27 1.27)
				)
				(justify mirror)
			)
		)
		(duplicate_pad_numbers_are_jumpers no)
		(fp_line
			(start -0.7874 0.4064)
			(end 0.7874 0.4064)
			(stroke
				(width 0.1524)
				(type default)
			)
			(layer "B.SilkS")
		)
		(fp_line
			(start 0.7874 0.4064)
			(end 0.7874 -0.4064)
			(stroke
				(width 0.1524)
				(type default)
			)
			(layer "B.SilkS")
		)
		(fp_line
			(start -0.7874 -0.4064)
			(end -0.7874 0.4064)
			(stroke
				(width 0.1524)
				(type default)
			)
			(layer "B.SilkS")
		)
		(fp_line
			(start 0.7874 -0.4064)
			(end -0.7874 -0.4064)
			(stroke
				(width 0.1524)
				(type default)
			)
			(layer "B.SilkS")
		)
		(fp_line
			(start -0.67945 0.3048)
			(end -0.120396 0.3048)
			(stroke
				(width 0.1)
				(type default)
			)
			(layer "B.Fab")
		)
		(fp_line
			(start -0.120396 0.3048)
			(end -0.120396 0.2794)
			(stroke
				(width 0.1)
				(type default)
			)
			(layer "B.Fab")
		)
		(fp_line
			(start 0.12065 0.3048)
			(end 0.67945 0.3048)
			(stroke
				(width 0.1)
				(type default)
			)
			(layer "B.Fab")
		)
		(fp_line
			(start 0.67945 0.3048)
			(end 0.67945 -0.305054)
			(stroke
				(width 0.1)
				(type default)
			)
			(layer "B.Fab")
		)
		(fp_line
			(start -0.120396 0.2794)
			(end 0.12065 0.2794)
			(stroke
				(width 0.1)
				(type default)
			)
			(layer "B.Fab")
		)
		(fp_line
			(start 0.12065 0.2794)
			(end 0.12065 0.3048)
			(stroke
				(width 0.1)
				(type default)
			)
			(layer "B.Fab")
		)
		(fp_line
			(start -0.12065 -0.2794)
			(end -0.12065 -0.3048)
			(stroke
				(width 0.1)
				(type default)
			)
			(layer "B.Fab")
		)
		(fp_line
			(start 0.12065 -0.2794)
			(end -0.12065 -0.2794)
			(stroke
				(width 0.1)
				(type default)
			)
			(layer "B.Fab")
		)
		(fp_line
			(start -0.67945 -0.3048)
			(end -0.67945 0.3048)
			(stroke
				(width 0.1)
				(type default)
			)
			(layer "B.Fab")
		)
		(fp_line
			(start -0.12065 -0.3048)
			(end -0.67945 -0.3048)
			(stroke
				(width 0.1)
				(type default)
			)
			(layer "B.Fab")
		)
		(fp_line
			(start 0.12065 -0.305054)
			(end 0.12065 -0.2794)
			(stroke
				(width 0.1)
				(type default)
			)
			(layer "B.Fab")
		)
		(fp_line
			(start 0.67945 -0.305054)
			(end 0.12065 -0.305054)
			(stroke
				(width 0.1)
				(type default)
			)
			(layer "B.Fab")
		)
		(pad "1" smd circle
			(at 0.40005 0 90)
			(size 0 0)
			(layers "B.Cu" "B.Mask" "B.Paste")
			(net "P3V3_AUX")
		)
		(pad "2" smd circle
			(at -0.40005 0 90)
			(size 0 0)
			(layers "B.Cu" "B.Mask" "B.Paste")
			(net "GND")
		)
	)
	(footprint ""
		(layer "B.Cu")
		(at 435.59857 -193.567304 -90)
		(property "Reference" "R839"
			(at 0 0 90)
			(layer "B.SilkS")
			(hide yes)
			(effects
				(font
					(size 1.27 1.27)
				)
				(justify mirror)
			)
		)
		(property "Value" ""
			(at 0 0 90)
			(layer "B.Fab")
			(effects
				(font
					(size 1.27 1.27)
				)
				(justify mirror)
			)
		)
		(duplicate_pad_numbers_are_jumpers no)
		(fp_line
			(start -0.7874 0.4064)
			(end 0.7874 0.4064)
			(stroke
				(width 0.1524)
				(type default)
			)
			(layer "B.SilkS")
		)
		(fp_line
			(start 0.7874 0.4064)
			(end 0.7874 -0.4064)
			(stroke
				(width 0.1524)
				(type default)
			)
			(layer "B.SilkS")
		)
		(fp_line
			(start -0.7874 -0.4064)
			(end -0.7874 0.4064)
			(stroke
				(width 0.1524)
				(type default)
			)
			(layer "B.SilkS")
		)
		(fp_line
			(start 0.7874 -0.4064)
			(end -0.7874 -0.4064)
			(stroke
				(width 0.1524)
				(type default)
			)
			(layer "B.SilkS")
		)
		(fp_line
			(start -0.67945 0.3048)
			(end -0.120396 0.3048)
			(stroke
				(width 0.1)
				(type default)
			)
			(layer "B.Fab")
		)
		(fp_line
			(start -0.120396 0.3048)
			(end -0.120396 0.2794)
			(stroke
				(width 0.1)
				(type default)
			)
			(layer "B.Fab")
		)
		(fp_line
			(start 0.12065 0.3048)
			(end 0.67945 0.3048)
			(stroke
				(width 0.1)
				(type default)
			)
			(layer "B.Fab")
		)
		(fp_line
			(start 0.67945 0.3048)
			(end 0.67945 -0.305054)
			(stroke
				(width 0.1)
				(type default)
			)
			(layer "B.Fab")
		)
		(fp_line
			(start -0.120396 0.2794)
			(end 0.12065 0.2794)
			(stroke
				(width 0.1)
				(type default)
			)
			(layer "B.Fab")
		)
		(fp_line
			(start 0.12065 0.2794)
			(end 0.12065 0.3048)
			(stroke
				(width 0.1)
				(type default)
			)
			(layer "B.Fab")
		)
		(fp_line
			(start -0.12065 -0.2794)
			(end -0.12065 -0.3048)
			(stroke
				(width 0.1)
				(type default)
			)
			(layer "B.Fab")
		)
		(fp_line
			(start 0.12065 -0.2794)
			(end -0.12065 -0.2794)
			(stroke
				(width 0.1)
				(type default)
			)
			(layer "B.Fab")
		)
		(fp_line
			(start -0.67945 -0.3048)
			(end -0.67945 0.3048)
			(stroke
				(width 0.1)
				(type default)
			)
			(layer "B.Fab")
		)
		(fp_line
			(start -0.12065 -0.3048)
			(end -0.67945 -0.3048)
			(stroke
				(width 0.1)
				(type default)
			)
			(layer "B.Fab")
		)
		(fp_line
			(start 0.12065 -0.305054)
			(end 0.12065 -0.2794)
			(stroke
				(width 0.1)
				(type default)
			)
			(layer "B.Fab")
		)
		(fp_line
			(start 0.67945 -0.305054)
			(end 0.12065 -0.305054)
			(stroke
				(width 0.1)
				(type default)
			)
			(layer "B.Fab")
		)
		(pad "1" smd circle
			(at 0.40005 0 90)
			(size 0 0)
			(layers "B.Cu" "B.Mask" "B.Paste")
			(net "PVCCD_HV_CPU0")
		)
		(pad "2" smd circle
			(at -0.40005 0 90)
			(size 0 0)
			(layers "B.Cu" "B.Mask" "B.Paste")
			(net "RST_M_GH_CPU0_FPGA_N")
		)
	)
	(footprint ""
		(layer "B.Cu")
		(at 297.876214 -321.549776 -90)
		(property "Reference" "C13"
			(at 0 0 90)
			(layer "B.SilkS")
			(hide yes)
			(effects
				(font
					(size 1.27 1.27)
				)
				(justify mirror)
			)
		)
		(property "Value" ""
			(at 0 0 90)
			(layer "B.Fab")
			(effects
				(font
					(size 1.27 1.27)
				)
				(justify mirror)
			)
		)
		(duplicate_pad_numbers_are_jumpers no)
		(fp_line
			(start -1.524 0.762)
			(end 1.524 0.762)
			(stroke
				(width 0.1524)
				(type default)
			)
			(layer "B.SilkS")
		)
		(fp_line
			(start 1.524 0.762)
			(end 1.524 -0.762)
			(stroke
				(width 0.1524)
				(type default)
			)
			(layer "B.SilkS")
		)
		(fp_line
			(start -1.524 -0.762)
			(end -1.524 0.762)
			(stroke
				(width 0.1524)
				(type default)
			)
			(layer "B.SilkS")
		)
		(fp_line
			(start 1.524 -0.762)
			(end -1.524 -0.762)
			(stroke
				(width 0.1524)
				(type default)
			)
			(layer "B.SilkS")
		)
		(fp_line
			(start -1.1049 0.724916)
			(end -1.1049 -0.724916)
			(stroke
				(width 0.1)
				(type default)
			)
			(layer "B.Fab")
		)
		(fp_line
			(start 1.1049 0.724916)
			(end -1.1049 0.724916)
			(stroke
				(width 0.1)
				(type default)
			)
			(layer "B.Fab")
		)
		(fp_line
			(start -1.1049 -0.724916)
			(end 1.1049 -0.724916)
			(stroke
				(width 0.1)
				(type default)
			)
			(layer "B.Fab")
		)
		(fp_line
			(start 1.1049 -0.724916)
			(end 1.1049 0.724916)
			(stroke
				(width 0.1)
				(type default)
			)
			(layer "B.Fab")
		)
		(pad "1" smd rect
			(at 0.889 0 270)
			(size 1.016 1.27)
			(layers "B.Cu" "B.Mask" "B.Paste")
			(net "P12V_S3_AUX_CPU0_NVDIMM")
		)
		(pad "2" smd rect
			(at -0.889 0 270)
			(size 1.016 1.27)
			(layers "B.Cu" "B.Mask" "B.Paste")
			(net "GND")
		)
	)
	(footprint ""
		(layer "B.Cu")
		(at 157.02788 -116.296948 180)
		(property "Reference" "R3480"
			(at 0 0 0)
			(layer "B.SilkS")
			(hide yes)
			(effects
				(font
					(size 1.27 1.27)
				)
				(justify mirror)
			)
		)
		(property "Value" ""
			(at 0 0 0)
			(layer "B.Fab")
			(effects
				(font
					(size 1.27 1.27)
				)
				(justify mirror)
			)
		)
		(duplicate_pad_numbers_are_jumpers no)
		(fp_line
			(start 0.7874 0.4064)
			(end 0.7874 -0.4064)
			(stroke
				(width 0.1524)
				(type default)
			)
			(layer "B.SilkS")
		)
		(fp_line
			(start 0.7874 -0.4064)
			(end -0.7874 -0.4064)
			(stroke
				(width 0.1524)
				(type default)
			)
			(layer "B.SilkS")
		)
		(fp_line
			(start -0.7874 0.4064)
			(end 0.7874 0.4064)
			(stroke
				(width 0.1524)
				(type default)
			)
			(layer "B.SilkS")
		)
		(fp_line
			(start -0.7874 -0.4064)
			(end -0.7874 0.4064)
			(stroke
				(width 0.1524)
				(type default)
			)
			(layer "B.SilkS")
		)
		(fp_line
			(start 0.67945 0.3048)
			(end 0.67945 -0.305054)
			(stroke
				(width 0.1)
				(type default)
			)
			(layer "B.Fab")
		)
		(fp_line
			(start 0.67945 -0.305054)
			(end 0.12065 -0.305054)
			(stroke
				(width 0.1)
				(type default)
			)
			(layer "B.Fab")
		)
		(fp_line
			(start 0.12065 0.3048)
			(end 0.67945 0.3048)
			(stroke
				(width 0.1)
				(type default)
			)
			(layer "B.Fab")
		)
		(fp_line
			(start 0.12065 0.2794)
			(end 0.12065 0.3048)
			(stroke
				(width 0.1)
				(type default)
			)
			(layer "B.Fab")
		)
		(fp_line
			(start 0.12065 -0.2794)
			(end -0.12065 -0.2794)
			(stroke
				(width 0.1)
				(type default)
			)
			(layer "B.Fab")
		)
		(fp_line
			(start 0.12065 -0.305054)
			(end 0.12065 -0.2794)
			(stroke
				(width 0.1)
				(type default)
			)
			(layer "B.Fab")
		)
		(fp_line
			(start -0.120396 0.3048)
			(end -0.120396 0.2794)
			(stroke
				(width 0.1)
				(type default)
			)
			(layer "B.Fab")
		)
		(fp_line
			(start -0.120396 0.2794)
			(end 0.12065 0.2794)
			(stroke
				(width 0.1)
				(type default)
			)
			(layer "B.Fab")
		)
		(fp_line
			(start -0.12065 -0.2794)
			(end -0.12065 -0.3048)
			(stroke
				(width 0.1)
				(type default)
			)
			(layer "B.Fab")
		)
		(fp_line
			(start -0.12065 -0.3048)
			(end -0.67945 -0.3048)
			(stroke
				(width 0.1)
				(type default)
			)
			(layer "B.Fab")
		)
		(fp_line
			(start -0.67945 0.3048)
			(end -0.120396 0.3048)
			(stroke
				(width 0.1)
				(type default)
			)
			(layer "B.Fab")
		)
		(fp_line
			(start -0.67945 -0.3048)
			(end -0.67945 0.3048)
			(stroke
				(width 0.1)
				(type default)
			)
			(layer "B.Fab")
		)
		(pad "1" smd circle
			(at 0.40005 0)
			(size 0 0)
			(layers "B.Cu" "B.Mask" "B.Paste")
			(net "GPU_BASE_HMC_READY_ISO")
		)
		(pad "2" smd circle
			(at -0.40005 0)
			(size 0 0)
			(layers "B.Cu" "B.Mask" "B.Paste")
			(net "GPU_BASE_HMC_READY_ISO_R")
		)
	)
)
